(kicad_pcb
	(version 20260206)
	(generator "pcbnew")
	(generator_version "10.0")
	(general
		(thickness 1.6)
		(legacy_teardrops no)
	)
	(paper "A4")
	(title_block
		(title "01162023_DA0F0TEBIF0_F0T_Expander_BD_F_brd_V02_OCP.brd")
		(comment 1 "Grand Teton / footprints 2844-2849 of 9728")
	)
	(layers
		(0 "F.Cu" signal "TOP")
		(4 "In1.Cu" signal "GND")
		(6 "In2.Cu" signal "VCC")
		(8 "In3.Cu" signal "VCC1")
		(10 "In4.Cu" signal "GND1")
		(12 "In5.Cu" signal "IN1")
		(14 "In6.Cu" signal "GND2")
		(16 "In7.Cu" signal "IN2")
		(18 "In8.Cu" signal "GND3")
		(20 "In9.Cu" signal "IN3")
		(22 "In10.Cu" signal "GND4")
		(24 "In11.Cu" signal "IN4")
		(26 "In12.Cu" signal "GND5")
		(28 "In13.Cu" signal "IN5")
		(30 "In14.Cu" signal "GND6")
		(32 "In15.Cu" signal "IN6")
		(34 "In16.Cu" signal "GND7")
		(2 "B.Cu" signal "BOTTOM")
		(9 "F.Adhes" user "F.Adhesive")
		(11 "B.Adhes" user "B.Adhesive")
		(13 "F.Paste" user "Package Geometry/Pastemask Top")
		(15 "B.Paste" user "Package Geometry/Pastemask Bottom")
		(5 "F.SilkS" user "Ref Des/Silkscreen Top")
		(7 "B.SilkS" user "Ref Des/Silkscreen Bottom")
		(1 "F.Mask" user "Board Geometry/Soldermask Top")
		(3 "B.Mask" user "Board Geometry/Soldermask Bottom")
		(17 "Dwgs.User" user "User.Drawings")
		(19 "Cmts.User" user "User.Comments")
		(21 "Eco1.User" user "User.Eco1")
		(23 "Eco2.User" user "User.Eco2")
		(25 "Edge.Cuts" user "Board Geometry/Outline")
		(27 "Margin" user)
		(31 "F.CrtYd" user "Package Geometry/Place Bound Top")
		(29 "B.CrtYd" user "Package Geometry/Place Bound Bottom")
		(35 "F.Fab" user "Ref Des/Assembly Top")
		(33 "B.Fab" user "Ref Des/Assembly Bottom")
	)
	(footprint ""
		(layer "F.Cu")
		(at 452.910448 -18.61439 90)
		(property "Reference" "U141"
			(at -1.13919 2.766822 90)
			(unlocked yes)
			(layer "F.SilkS")
			(effects
				(font
					(size 0.7874 0.5842)
					(thickness 0.1524)
				)
				(justify left)
			)
		)
		(property "Value" ""
			(at 0 0 90)
			(layer "F.Fab")
			(effects
				(font
					(size 1.27 1.27)
				)
			)
		)
		(duplicate_pad_numbers_are_jumpers no)
		(fp_line
			(start 1.463548 -1.549908)
			(end 1.463548 1.549908)
			(stroke
				(width 0.1524)
				(type default)
			)
			(layer "F.SilkS")
		)
		(fp_line
			(start 0.762 -1.549908)
			(end 1.463548 -1.549908)
			(stroke
				(width 0.1524)
				(type default)
			)
			(layer "F.SilkS")
		)
		(fp_line
			(start -0.787908 -1.549908)
			(end 0 -0.762)
			(stroke
				(width 0.1524)
				(type default)
			)
			(layer "F.SilkS")
		)
		(fp_line
			(start -1.463548 -1.549908)
			(end -0.787908 -1.549908)
			(stroke
				(width 0.1524)
				(type default)
			)
			(layer "F.SilkS")
		)
		(fp_line
			(start 0 -0.762)
			(end 0.762 -1.549908)
			(stroke
				(width 0.1524)
				(type default)
			)
			(layer "F.SilkS")
		)
		(fp_line
			(start 1.463548 1.549908)
			(end -1.463548 1.549908)
			(stroke
				(width 0.1524)
				(type default)
			)
			(layer "F.SilkS")
		)
		(fp_line
			(start -1.463548 1.549908)
			(end -1.463548 -1.549908)
			(stroke
				(width 0.1524)
				(type default)
			)
			(layer "F.SilkS")
		)
		(fp_poly
			(pts
				(xy -3.4798 -1.359916) (xy -2.86004 -1.050036) (xy -3.4798 -0.740156)
			)
			(stroke
				(width 0)
				(type default)
			)
			(fill yes)
			(layer "F.SilkS")
		)
		(fp_line
			(start 1.549908 -1.549908)
			(end 1.549908 1.549908)
			(stroke
				(width 0.1)
				(type default)
			)
			(layer "F.Fab")
		)
		(fp_line
			(start -1.549908 -1.549908)
			(end 1.549908 -1.549908)
			(stroke
				(width 0.1)
				(type default)
			)
			(layer "F.Fab")
		)
		(fp_line
			(start 1.549908 1.549908)
			(end -1.549908 1.549908)
			(stroke
				(width 0.1)
				(type default)
			)
			(layer "F.Fab")
		)
		(fp_line
			(start -1.549908 1.549908)
			(end -1.549908 -1.549908)
			(stroke
				(width 0.1)
				(type default)
			)
			(layer "F.Fab")
		)
		(fp_poly
			(pts
				(xy -3.4798 -1.359916) (xy -2.86004 -1.050036) (xy -3.4798 -0.740156)
			)
			(stroke
				(width 0)
				(type default)
			)
			(fill yes)
			(layer "F.Fab")
		)
		(pad "1" smd rect
			(at -2.175002 -1.050036 180)
			(size 0.6096 1.1684)
			(layers "F.Cu" "F.Mask" "F.Paste")
			(net "P3V3_SSD15")
		)
		(pad "2" smd rect
			(at -2.175002 -0.32512 180)
			(size 0.4318 1.1684)
			(layers "F.Cu" "F.Mask" "F.Paste")
			(net "SMB_ISO_SSD15_SCL")
		)
		(pad "3" smd rect
			(at -2.175002 0.32512 180)
			(size 0.4318 1.1684)
			(layers "F.Cu" "F.Mask" "F.Paste")
			(net "SMB_ISO_SSD15_SDA")
		)
		(pad "4" smd rect
			(at -2.175002 1.050036 180)
			(size 0.6096 1.1684)
			(layers "F.Cu" "F.Mask" "F.Paste")
			(net "GND")
		)
		(pad "5" smd rect
			(at 2.175002 1.050036 180)
			(size 0.6096 1.1684)
			(layers "F.Cu" "F.Mask" "F.Paste")
			(net "SMB_SSD15_ISO_EN")
		)
		(pad "6" smd rect
			(at 2.175002 0.32512 180)
			(size 0.4318 1.1684)
			(layers "F.Cu" "F.Mask" "F.Paste")
			(net "SMB_BIC_I2C9_MUX1_SSD15_R_SDA")
		)
		(pad "7" smd rect
			(at 2.175002 -0.32512 180)
			(size 0.4318 1.1684)
			(layers "F.Cu" "F.Mask" "F.Paste")
			(net "SMB_BIC_I2C9_MUX1_SSD15_R_SCL")
		)
		(pad "8" smd rect
			(at 2.175002 -1.050036 180)
			(size 0.6096 1.1684)
			(layers "F.Cu" "F.Mask" "F.Paste")
			(net "P3V3_AUX")
		)
	)
	(footprint ""
		(layer "F.Cu")
		(at 379.633988 -3.820922)
		(property "Reference" "R5823"
			(at 0 0 0)
			(layer "F.SilkS")
			(hide yes)
			(effects
				(font
					(size 1.27 1.27)
				)
			)
		)
		(property "Value" ""
			(at 0 0 0)
			(layer "F.Fab")
			(effects
				(font
					(size 1.27 1.27)
				)
			)
		)
		(duplicate_pad_numbers_are_jumpers no)
		(fp_line
			(start -0.7874 -0.4064)
			(end 0.7874 -0.4064)
			(stroke
				(width 0.1524)
				(type default)
			)
			(layer "F.SilkS")
		)
		(fp_line
			(start -0.7874 0.4064)
			(end -0.7874 -0.4064)
			(stroke
				(width 0.1524)
				(type default)
			)
			(layer "F.SilkS")
		)
		(fp_line
			(start 0.7874 -0.4064)
			(end 0.7874 0.4064)
			(stroke
				(width 0.1524)
				(type default)
			)
			(layer "F.SilkS")
		)
		(fp_line
			(start 0.7874 0.4064)
			(end -0.7874 0.4064)
			(stroke
				(width 0.1524)
				(type default)
			)
			(layer "F.SilkS")
		)
		(fp_line
			(start -0.67945 -0.305054)
			(end -0.12065 -0.305054)
			(stroke
				(width 0.1)
				(type default)
			)
			(layer "F.Fab")
		)
		(fp_line
			(start -0.67945 0.3048)
			(end -0.67945 -0.305054)
			(stroke
				(width 0.1)
				(type default)
			)
			(layer "F.Fab")
		)
		(fp_line
			(start -0.12065 -0.305054)
			(end -0.12065 -0.2794)
			(stroke
				(width 0.1)
				(type default)
			)
			(layer "F.Fab")
		)
		(fp_line
			(start -0.12065 -0.2794)
			(end 0.12065 -0.2794)
			(stroke
				(width 0.1)
				(type default)
			)
			(layer "F.Fab")
		)
		(fp_line
			(start -0.12065 0.2794)
			(end -0.12065 0.3048)
			(stroke
				(width 0.1)
				(type default)
			)
			(layer "F.Fab")
		)
		(fp_line
			(start -0.12065 0.3048)
			(end -0.67945 0.3048)
			(stroke
				(width 0.1)
				(type default)
			)
			(layer "F.Fab")
		)
		(fp_line
			(start 0.120396 0.2794)
			(end -0.12065 0.2794)
			(stroke
				(width 0.1)
				(type default)
			)
			(layer "F.Fab")
		)
		(fp_line
			(start 0.120396 0.3048)
			(end 0.120396 0.2794)
			(stroke
				(width 0.1)
				(type default)
			)
			(layer "F.Fab")
		)
		(fp_line
			(start 0.12065 -0.3048)
			(end 0.67945 -0.3048)
			(stroke
				(width 0.1)
				(type default)
			)
			(layer "F.Fab")
		)
		(fp_line
			(start 0.12065 -0.2794)
			(end 0.12065 -0.3048)
			(stroke
				(width 0.1)
				(type default)
			)
			(layer "F.Fab")
		)
		(fp_line
			(start 0.67945 -0.3048)
			(end 0.67945 0.3048)
			(stroke
				(width 0.1)
				(type default)
			)
			(layer "F.Fab")
		)
		(fp_line
			(start 0.67945 0.3048)
			(end 0.120396 0.3048)
			(stroke
				(width 0.1)
				(type default)
			)
			(layer "F.Fab")
		)
		(pad "1" smd circle
			(at -0.40005 0)
			(size 0 0)
			(layers "F.Cu" "F.Mask" "F.Paste")
			(net "LM75_3_A2")
		)
		(pad "2" smd circle
			(at 0.40005 0)
			(size 0 0)
			(layers "F.Cu" "F.Mask" "F.Paste")
			(net "GND")
		)
	)
	(footprint ""
		(layer "F.Cu")
		(at 17.83969 -214.151972 180)
		(property "Reference" "R6569"
			(at 0 0 180)
			(layer "F.SilkS")
			(hide yes)
			(effects
				(font
					(size 1.27 1.27)
				)
			)
		)
		(property "Value" ""
			(at 0 0 180)
			(layer "F.Fab")
			(effects
				(font
					(size 1.27 1.27)
				)
			)
		)
		(duplicate_pad_numbers_are_jumpers no)
		(fp_line
			(start 0.7874 0.4064)
			(end -0.7874 0.4064)
			(stroke
				(width 0.1524)
				(type default)
			)
			(layer "F.SilkS")
		)
		(fp_line
			(start 0.7874 -0.4064)
			(end 0.7874 0.4064)
			(stroke
				(width 0.1524)
				(type default)
			)
			(layer "F.SilkS")
		)
		(fp_line
			(start -0.7874 0.4064)
			(end -0.7874 -0.4064)
			(stroke
				(width 0.1524)
				(type default)
			)
			(layer "F.SilkS")
		)
		(fp_line
			(start -0.7874 -0.4064)
			(end 0.7874 -0.4064)
			(stroke
				(width 0.1524)
				(type default)
			)
			(layer "F.SilkS")
		)
		(fp_line
			(start 0.67945 0.3048)
			(end 0.120396 0.3048)
			(stroke
				(width 0.1)
				(type default)
			)
			(layer "F.Fab")
		)
		(fp_line
			(start 0.67945 -0.3048)
			(end 0.67945 0.3048)
			(stroke
				(width 0.1)
				(type default)
			)
			(layer "F.Fab")
		)
		(fp_line
			(start 0.12065 -0.2794)
			(end 0.12065 -0.3048)
			(stroke
				(width 0.1)
				(type default)
			)
			(layer "F.Fab")
		)
		(fp_line
			(start 0.12065 -0.3048)
			(end 0.67945 -0.3048)
			(stroke
				(width 0.1)
				(type default)
			)
			(layer "F.Fab")
		)
		(fp_line
			(start 0.120396 0.3048)
			(end 0.120396 0.2794)
			(stroke
				(width 0.1)
				(type default)
			)
			(layer "F.Fab")
		)
		(fp_line
			(start 0.120396 0.2794)
			(end -0.12065 0.2794)
			(stroke
				(width 0.1)
				(type default)
			)
			(layer "F.Fab")
		)
		(fp_line
			(start -0.12065 0.3048)
			(end -0.67945 0.3048)
			(stroke
				(width 0.1)
				(type default)
			)
			(layer "F.Fab")
		)
		(fp_line
			(start -0.12065 0.2794)
			(end -0.12065 0.3048)
			(stroke
				(width 0.1)
				(type default)
			)
			(layer "F.Fab")
		)
		(fp_line
			(start -0.12065 -0.2794)
			(end 0.12065 -0.2794)
			(stroke
				(width 0.1)
				(type default)
			)
			(layer "F.Fab")
		)
		(fp_line
			(start -0.12065 -0.305054)
			(end -0.12065 -0.2794)
			(stroke
				(width 0.1)
				(type default)
			)
			(layer "F.Fab")
		)
		(fp_line
			(start -0.67945 0.3048)
			(end -0.67945 -0.305054)
			(stroke
				(width 0.1)
				(type default)
			)
			(layer "F.Fab")
		)
		(fp_line
			(start -0.67945 -0.305054)
			(end -0.12065 -0.305054)
			(stroke
				(width 0.1)
				(type default)
			)
			(layer "F.Fab")
		)
		(pad "1" smd circle
			(at -0.40005 0 180)
			(size 0 0)
			(layers "F.Cu" "F.Mask" "F.Paste")
			(net "PWRGD_PEX0_P1V8_PLL_R")
		)
		(pad "2" smd circle
			(at 0.40005 0 180)
			(size 0 0)
			(layers "F.Cu" "F.Mask" "F.Paste")
			(net "PWRGD_PEX0_P1V8_PLL")
		)
	)
	(footprint ""
		(layer "F.Cu")
		(at 222.220028 -117.90045 90)
		(property "Reference" "PC621"
			(at 0 0 90)
			(layer "F.SilkS")
			(hide yes)
			(effects
				(font
					(size 1.27 1.27)
				)
			)
		)
		(property "Value" ""
			(at 0 0 90)
			(layer "F.Fab")
			(effects
				(font
					(size 1.27 1.27)
				)
			)
		)
		(duplicate_pad_numbers_are_jumpers no)
		(fp_line
			(start 1.524 -0.762)
			(end 1.524 0.762)
			(stroke
				(width 0.1524)
				(type default)
			)
			(layer "F.SilkS")
		)
		(fp_line
			(start -1.524 -0.762)
			(end 1.524 -0.762)
			(stroke
				(width 0.1524)
				(type default)
			)
			(layer "F.SilkS")
		)
		(fp_line
			(start 1.524 0.762)
			(end -1.524 0.762)
			(stroke
				(width 0.1524)
				(type default)
			)
			(layer "F.SilkS")
		)
		(fp_line
			(start -1.524 0.762)
			(end -1.524 -0.762)
			(stroke
				(width 0.1524)
				(type default)
			)
			(layer "F.SilkS")
		)
		(fp_line
			(start 1.1049 -0.724916)
			(end -1.1049 -0.724916)
			(stroke
				(width 0.1)
				(type default)
			)
			(layer "F.Fab")
		)
		(fp_line
			(start -1.1049 -0.724916)
			(end -1.1049 0.724916)
			(stroke
				(width 0.1)
				(type default)
			)
			(layer "F.Fab")
		)
		(fp_line
			(start 1.1049 0.724916)
			(end 1.1049 -0.724916)
			(stroke
				(width 0.1)
				(type default)
			)
			(layer "F.Fab")
		)
		(fp_line
			(start -1.1049 0.724916)
			(end 1.1049 0.724916)
			(stroke
				(width 0.1)
				(type default)
			)
			(layer "F.Fab")
		)
		(pad "1" smd rect
			(at -0.889 0 270)
			(size 1.016 1.27)
			(layers "F.Cu" "F.Mask" "F.Paste")
			(net "P12V_NIC3_R")
		)
		(pad "2" smd rect
			(at 0.889 0 270)
			(size 1.016 1.27)
			(layers "F.Cu" "F.Mask" "F.Paste")
			(net "GND")
		)
	)
	(footprint ""
		(layer "F.Cu")
		(at 63.56731 -171.675806)
		(property "Reference" "R49"
			(at 0 0 0)
			(layer "F.SilkS")
			(hide yes)
			(effects
				(font
					(size 1.27 1.27)
				)
			)
		)
		(property "Value" ""
			(at 0 0 0)
			(layer "F.Fab")
			(effects
				(font
					(size 1.27 1.27)
				)
			)
		)
		(duplicate_pad_numbers_are_jumpers no)
		(fp_line
			(start -0.7874 -0.4064)
			(end 0.7874 -0.4064)
			(stroke
				(width 0.1524)
				(type default)
			)
			(layer "F.SilkS")
		)
		(fp_line
			(start -0.7874 0.4064)
			(end -0.7874 -0.4064)
			(stroke
				(width 0.1524)
				(type default)
			)
			(layer "F.SilkS")
		)
		(fp_line
			(start 0.7874 -0.4064)
			(end 0.7874 0.4064)
			(stroke
				(width 0.1524)
				(type default)
			)
			(layer "F.SilkS")
		)
		(fp_line
			(start 0.7874 0.4064)
			(end -0.7874 0.4064)
			(stroke
				(width 0.1524)
				(type default)
			)
			(layer "F.SilkS")
		)
		(fp_line
			(start -0.67945 -0.305054)
			(end -0.12065 -0.305054)
			(stroke
				(width 0.1)
				(type default)
			)
			(layer "F.Fab")
		)
		(fp_line
			(start -0.67945 0.3048)
			(end -0.67945 -0.305054)
			(stroke
				(width 0.1)
				(type default)
			)
			(layer "F.Fab")
		)
		(fp_line
			(start -0.12065 -0.305054)
			(end -0.12065 -0.2794)
			(stroke
				(width 0.1)
				(type default)
			)
			(layer "F.Fab")
		)
		(fp_line
			(start -0.12065 -0.2794)
			(end 0.12065 -0.2794)
			(stroke
				(width 0.1)
				(type default)
			)
			(layer "F.Fab")
		)
		(fp_line
			(start -0.12065 0.2794)
			(end -0.12065 0.3048)
			(stroke
				(width 0.1)
				(type default)
			)
			(layer "F.Fab")
		)
		(fp_line
			(start -0.12065 0.3048)
			(end -0.67945 0.3048)
			(stroke
				(width 0.1)
				(type default)
			)
			(layer "F.Fab")
		)
		(fp_line
			(start 0.120396 0.2794)
			(end -0.12065 0.2794)
			(stroke
				(width 0.1)
				(type default)
			)
			(layer "F.Fab")
		)
		(fp_line
			(start 0.120396 0.3048)
			(end 0.120396 0.2794)
			(stroke
				(width 0.1)
				(type default)
			)
			(layer "F.Fab")
		)
		(fp_line
			(start 0.12065 -0.3048)
			(end 0.67945 -0.3048)
			(stroke
				(width 0.1)
				(type default)
			)
			(layer "F.Fab")
		)
		(fp_line
			(start 0.12065 -0.2794)
			(end 0.12065 -0.3048)
			(stroke
				(width 0.1)
				(type default)
			)
			(layer "F.Fab")
		)
		(fp_line
			(start 0.67945 -0.3048)
			(end 0.67945 0.3048)
			(stroke
				(width 0.1)
				(type default)
			)
			(layer "F.Fab")
		)
		(fp_line
			(start 0.67945 0.3048)
			(end 0.120396 0.3048)
			(stroke
				(width 0.1)
				(type default)
			)
			(layer "F.Fab")
		)
		(pad "1" smd circle
			(at -0.40005 0)
			(size 0 0)
			(layers "F.Cu" "F.Mask" "F.Paste")
			(net "P3V3_NIC0")
		)
		(pad "2" smd circle
			(at 0.40005 0)
			(size 0 0)
			(layers "F.Cu" "F.Mask" "F.Paste")
			(net "HP_NIC0_PWRGD")
		)
	)
	(footprint ""
		(layer "F.Cu")
		(at 359.422192 -284.834838 90)
		(property "Reference" "PC189"
			(at 0 0 90)
			(layer "F.SilkS")
			(hide yes)
			(effects
				(font
					(size 1.27 1.27)
				)
			)
		)
		(property "Value" ""
			(at 0 0 90)
			(layer "F.Fab")
			(effects
				(font
					(size 1.27 1.27)
				)
			)
		)
		(duplicate_pad_numbers_are_jumpers no)
		(fp_line
			(start 0.7874 -0.4064)
			(end 0.7874 0.4064)
			(stroke
				(width 0.1524)
				(type default)
			)
			(layer "F.SilkS")
		)
		(fp_line
			(start -0.7874 -0.4064)
			(end 0.7874 -0.4064)
			(stroke
				(width 0.1524)
				(type default)
			)
			(layer "F.SilkS")
		)
		(fp_line
			(start 0.7874 0.4064)
			(end -0.7874 0.4064)
			(stroke
				(width 0.1524)
				(type default)
			)
			(layer "F.SilkS")
		)
		(fp_line
			(start -0.7874 0.4064)
			(end -0.7874 -0.4064)
			(stroke
				(width 0.1524)
				(type default)
			)
			(layer "F.SilkS")
		)
		(fp_line
			(start -0.12065 -0.305054)
			(end -0.12065 -0.2794)
			(stroke
				(width 0.1)
				(type default)
			)
			(layer "F.Fab")
		)
		(fp_line
			(start -0.67945 -0.305054)
			(end -0.12065 -0.305054)
			(stroke
				(width 0.1)
				(type default)
			)
			(layer "F.Fab")
		)
		(fp_line
			(start 0.67945 -0.3048)
			(end 0.67945 0.3048)
			(stroke
				(width 0.1)
				(type default)
			)
			(layer "F.Fab")
		)
		(fp_line
			(start 0.12065 -0.3048)
			(end 0.67945 -0.3048)
			(stroke
				(width 0.1)
				(type default)
			)
			(layer "F.Fab")
		)
		(fp_line
			(start 0.12065 -0.2794)
			(end 0.12065 -0.3048)
			(stroke
				(width 0.1)
				(type default)
			)
			(layer "F.Fab")
		)
		(fp_line
			(start -0.12065 -0.2794)
			(end 0.12065 -0.2794)
			(stroke
				(width 0.1)
				(type default)
			)
			(layer "F.Fab")
		)
		(fp_line
			(start 0.120396 0.2794)
			(end -0.12065 0.2794)
			(stroke
				(width 0.1)
				(type default)
			)
			(layer "F.Fab")
		)
		(fp_line
			(start -0.12065 0.2794)
			(end -0.12065 0.3048)
			(stroke
				(width 0.1)
				(type default)
			)
			(layer "F.Fab")
		)
		(fp_line
			(start 0.67945 0.3048)
			(end 0.120396 0.3048)
			(stroke
				(width 0.1)
				(type default)
			)
			(layer "F.Fab")
		)
		(fp_line
			(start 0.120396 0.3048)
			(end 0.120396 0.2794)
			(stroke
				(width 0.1)
				(type default)
			)
			(layer "F.Fab")
		)
		(fp_line
			(start -0.12065 0.3048)
			(end -0.67945 0.3048)
			(stroke
				(width 0.1)
				(type default)
			)
			(layer "F.Fab")
		)
		(fp_line
			(start -0.67945 0.3048)
			(end -0.67945 -0.305054)
			(stroke
				(width 0.1)
				(type default)
			)
			(layer "F.Fab")
		)
		(pad "1" smd circle
			(at -0.40005 0 90)
			(size 0 0)
			(layers "F.Cu" "F.Mask" "F.Paste")
			(net "SW_P12V_P0V8_PEX3_FLT")
		)
		(pad "2" smd circle
			(at 0.40005 0 90)
			(size 0 0)
			(layers "F.Cu" "F.Mask" "F.Paste")
			(net "GND")
		)
	)
)
